FILE_TYPE = CONNECTIVITY;
{Allegro Design Entry HDL 16.6-p007 (v16-6-112F) 10/10/2012}
"PAGE_NUMBER" = 159;
0"NC";
1"SMB_HOST_STBY_LVC3_SDA";
2"P3V3_STBY\g";
3"P3V3_STBY\g";
4"P3V3_STBY\g";
5"P3V3_STBY\g";
6"SMB_OCP_FRU_STBY_LVC3_SDA";
7"SMB_OCP_FRU_STBY_LVC3_SCL";
8"SMB_OCP_FRU_STBY_LVC3_SCL_R";
9"SMB_OCP_FRU_STBY_LVC3_SDA_R";
10"SMB_BMC_PMBUS_STBY_LVC3_SDA";
11"SMB_BMC_PMBUS_STBY_LVC3_SCL";
12"SMB_VR_STBY_LVC3_SCL";
13"SMB_VR_STBY_LVC3_SDA";
14"SMB_VR_STBY_LVC3_SCL_R";
15"SMB_VR_STBY_LVC3_SDA_R";
16"SMB_BMC_PMBUS_STBY_LVC3_SDA_R";
17"SMB_BMC_PMBUS_STBY_LVC3_SCL_R";
18"SMB_SMLINK0_STBY_LVC3_SCL";
19"SMB_SMLINK0_STBY_LVC3_SDA";
20"SMB_OCP_LAN_STBY_LVC3_SCL";
21"SMB_OCP_LAN_STBY_LVC3_SDA";
22"SMB_HOST_STBY_LVC3_SCL";
23"SMB_OCP_LAN_STBY_LVC3_SCL_R";
24"SMB_OCP_LAN_STBY_LVC3_SDA_R";
25"SMB_SPRINGVILLE_STBY_LVC3_SDA";
26"SMB_SPRINGVILLE_STBY_LVC3_SCL";
27"SMB_OCP_LAN_STBY_LVC3_SCL";
28"SMB_OCP_LAN_STBY_LVC3_SDA";
29"SMB_SMLINK0_STBY_LVC3_SCL";
30"SMB_SMLINK0_STBY_LVC3_SDA";
31"SMB_HOST_STBY_LVC3_SCL_R";
32"SMB_HOST_STBY_LVC3_SDA_R";
33"SMB_SMLINK0_STBY_LVC3_SCL_R";
34"SMB_SMLINK0_STBY_LVC3_SDA_R";
%"P3V3_STBY"
"1","(-3375,3200)","0","mstr_symbols","I209";
;
BODY_TYPE"PLUMBING"
CDS_LIB"mstr_symbols"
SIZE"1B"
VOLTAGE"3.3V"
HDL_POWER"P3V3_STBY";
"G\NAC"2;
%"RES"
"2","(-3375,2900)","0","mstr_discrete","I210";
;
$SEC"1"
CDS_SEC"1"
BOM_COST"SM_CONTROLLER"
SKU"B"
ROOM"SMBUS"
CDS_LOCATION"R8G3"
CDS_LIB"mstr_discrete"
PART_NUMBER"G21796-311"
WATTAGE"1/16W"
PACK_TYPE"0402"
TOLERANCE"1.0%"
VALUE"2.26K"
LOCATION"R8G3"
MATERIAL"EMPTY";
"A"
$PN"1"2;
"B"
$PN"2"23;
%"P3V3_STBY"
"1","(-3725,3200)","0","mstr_symbols","I211";
;
SIZE"1B"
CDS_LIB"mstr_symbols"
BODY_TYPE"PLUMBING"
VOLTAGE"3.3V"
HDL_POWER"P3V3_STBY";
"G\NAC"3;
%"RES"
"2","(-3725,2900)","0","mstr_discrete","I212";
;
SKU"B"
BOM_COST"SM_CONTROLLER"
CDS_SEC"1"
$SEC"1"
ROOM"SMBUS"
CDS_LOCATION"R8G6"
CDS_LIB"mstr_discrete"
WATTAGE"1/16W"
PACK_TYPE"0402"
TOLERANCE"1.0%"
VALUE"2.26K"
PART_NUMBER"G21796-311"
LOCATION"R8G6"
MATERIAL"EMPTY";
"A"
$PN"1"3;
"B"
$PN"2"24;
%"P3V3_STBY"
"1","(550,5125)","0","mstr_symbols","I213";
;
CDS_LIB"mstr_symbols"
SIZE"1B"
BODY_TYPE"PLUMBING"
VOLTAGE"3.3V"
HDL_POWER"P3V3_STBY";
"G\NAC"4;
%"RES"
"2","(550,4825)","0","mstr_discrete","I214";
;
BOM_COST"SM_CONTROLLER"
CDS_SEC"1"
$SEC"1"
SKU"B"
ROOM"SMBUS"
CDS_LOCATION"R2U5"
CDS_LIB"mstr_discrete"
PART_NUMBER"G21796-311"
VALUE"2.26K"
LOCATION"R2U5"
TOLERANCE"1.0%"
PACK_TYPE"0402"
MATERIAL"CHIP"
WATTAGE"1/16W";
"A"
$PN"1"4;
"B"
$PN"2"8;
%"P3V3_STBY"
"1","(200,5125)","0","mstr_symbols","I215";
;
SIZE"1B"
CDS_LIB"mstr_symbols"
BODY_TYPE"PLUMBING"
VOLTAGE"3.3V"
HDL_POWER"P3V3_STBY";
"G\NAC"5;
%"RES"
"2","(200,4825)","0","mstr_discrete","I216";
;
BOM_COST"SM_CONTROLLER"
$SEC"1"
CDS_SEC"1"
ROOM"SMBUS"
SKU"B"
CDS_LOCATION"R2U13"
CDS_LIB"mstr_discrete"
PART_NUMBER"G21796-311"
PACK_TYPE"0402"
WATTAGE"1/16W"
MATERIAL"CHIP"
LOCATION"R2U13"
TOLERANCE"1.0%"
VALUE"2.26K";
"A"
$PN"1"5;
"B"
$PN"2"9;
%"RES"
"1","(700,3375)","0","mstr_discrete","I218";
;
CDS_SEC"1"
$SEC"1"
PACK_TYPE"0402"
BOM_COST"SM_CONTROLLER"
ROOM"SMBUS"
PART_NUMBER"G21796-173"
CDS_LIB"mstr_discrete"
CDS_LOCATION"R2U1"
WATTAGE"1/16W"
TOLERANCE"1%"
VALUE"20.0"
LOCATION"R2U1"
MATERIAL"CHIP";
"B"
$PN"2"11;
"A"
$PN"1"17;
%"RES"
"1","(700,3550)","0","mstr_discrete","I219";
;
BOM_COST"SM_CONTROLLER"
CDS_SEC"1"
$SEC"1"
CDS_LOCATION"R2T49"
ROOM"SMBUS"
PART_NUMBER"G21796-173"
CDS_LIB"mstr_discrete"
PACK_TYPE"0402"
WATTAGE"1/16W"
LOCATION"R2T49"
TOLERANCE"1%"
VALUE"20.0"
MATERIAL"CHIP";
"B"
$PN"2"10;
"A"
$PN"1"16;
%"RES"
"1","(1025,4275)","0","mstr_discrete","I220";
;
CDS_LIB"mstr_discrete"
PACK_TYPE"0402"
$SEC"1"
CDS_SEC"1"
BOM_COST"SM_CONTROLLER"
ROOM"SMBUS"
PART_NUMBER"G21796-173"
CDS_LOCATION"R2U7"
WATTAGE"1/16W"
VALUE"20.0"
TOLERANCE"1%"
LOCATION"R2U7"
MATERIAL"CHIP";
"B"
$PN"2"7;
"A"
$PN"1"8;
%"RES"
"1","(1025,4450)","0","mstr_discrete","I221";
;
CDS_LIB"mstr_discrete"
PACK_TYPE"0402"
CDS_SEC"1"
$SEC"1"
BOM_COST"SM_CONTROLLER"
CDS_LOCATION"R2U10"
ROOM"SMBUS"
PART_NUMBER"G21796-173"
WATTAGE"1/16W"
VALUE"20.0"
TOLERANCE"1%"
LOCATION"R2U10"
MATERIAL"CHIP";
"B"
$PN"2"6;
"A"
$PN"1"9;
%"RES"
"1","(700,1600)","0","mstr_discrete","I222";
;
CDS_SEC"1"
$SEC"1"
BOM_COST"SM_CONTROLLER"
ROOM"SMBUS"
PART_NUMBER"G21497-005"
CDS_LOCATION"R1U11"
CDS_LIB"mstr_discrete"
PACK_TYPE"0402"
WATTAGE"1/16W"
TOLERANCE"5%"
VALUE"0.0"
LOCATION"R1U11"
MATERIAL"CHIP";
"B"
$PN"2"12;
"A"
$PN"1"14;
%"RES"
"1","(700,1775)","0","mstr_discrete","I223";
;
PACK_TYPE"0402"
BOM_COST"SM_CONTROLLER"
CDS_SEC"1"
$SEC"1"
CDS_LOCATION"R1U8"
ROOM"SMBUS"
PART_NUMBER"G21497-005"
CDS_LIB"mstr_discrete"
WATTAGE"1/16W"
TOLERANCE"5%"
VALUE"0.0"
LOCATION"R1U8"
MATERIAL"CHIP";
"B"
$PN"2"13;
"A"
$PN"1"15;
%"RES"
"1","(-3625,1575)","0","mstr_discrete","I224";
;
PACK_TYPE"0402"
CDS_SEC"1"
$SEC"1"
ROOM"SMBUS"
BOM_COST"SM_CONTROLLER"
PART_NUMBER"G21796-173"
CDS_LIB"mstr_discrete"
CDS_LOCATION"R9G12"
WATTAGE"1/16W"
TOLERANCE"1%"
VALUE"20.0"
LOCATION"R9G12"
MATERIAL"CHIP";
"B"
$PN"2"25;
"A"
$PN"1"28;
%"RES"
"1","(-3625,1450)","0","mstr_discrete","I225";
;
PACK_TYPE"0402"
CDS_SEC"1"
$SEC"1"
BOM_COST"SM_CONTROLLER"
ROOM"SMBUS"
PART_NUMBER"G21796-173"
CDS_LIB"mstr_discrete"
CDS_LOCATION"R1U20"
WATTAGE"1/16W"
VALUE"20.0"
TOLERANCE"1%"
LOCATION"R1U20"
MATERIAL"CHIP";
"B"
$PN"2"25;
"A"
$PN"1"30;
%"RES"
"1","(-3625,1325)","0","mstr_discrete","I226";
;
PACK_TYPE"0402"
CDS_SEC"1"
$SEC"1"
BOM_COST"SM_CONTROLLER"
ROOM"SMBUS"
PART_NUMBER"G21796-173"
CDS_LIB"mstr_discrete"
CDS_LOCATION"R1U19"
WATTAGE"1/16W"
VALUE"20.0"
TOLERANCE"1%"
LOCATION"R1U19"
MATERIAL"CHIP";
"B"
$PN"2"26;
"A"
$PN"1"29;
%"RES"
"1","(-3625,1200)","0","mstr_discrete","I227";
;
PACK_TYPE"0402"
CDS_SEC"1"
$SEC"1"
ROOM"SMBUS"
BOM_COST"SM_CONTROLLER"
PART_NUMBER"G21796-173"
CDS_LIB"mstr_discrete"
CDS_LOCATION"R9G13"
WATTAGE"1/16W"
VALUE"20.0"
TOLERANCE"1%"
LOCATION"R9G13"
MATERIAL"CHIP";
"B"
$PN"2"26;
"A"
$PN"1"27;
%"RES"
"1","(-2875,2525)","0","mstr_discrete","I228";
;
BOM_COST"SM_CONTROLLER"
CDS_SEC"1"
$SEC"1"
CDS_LOCATION"R8G5"
ROOM"SMBUS"
PART_NUMBER"G21796-173"
CDS_LIB"mstr_discrete"
PACK_TYPE"0402"
WATTAGE"1/16W"
LOCATION"R8G5"
TOLERANCE"1%"
VALUE"20.0"
MATERIAL"CHIP";
"B"
$PN"2"21;
"A"
$PN"1"24;
%"RES"
"1","(-2875,2350)","0","mstr_discrete","I229";
;
CDS_SEC"1"
$SEC"1"
PACK_TYPE"0402"
BOM_COST"SM_CONTROLLER"
ROOM"SMBUS"
PART_NUMBER"G21796-173"
CDS_LIB"mstr_discrete"
CDS_LOCATION"R8G4"
WATTAGE"1/16W"
TOLERANCE"1%"
VALUE"20.0"
LOCATION"R8G4"
MATERIAL"CHIP";
"B"
$PN"2"20;
"A"
$PN"1"23;
%"RES"
"1","(-3175,3600)","0","mstr_discrete","I230";
;
PACK_TYPE"0402"
CDS_SEC"1"
CDS_LIB"mstr_discrete"
BOM_COST"SM_CONTROLLER"
$SEC"1"
CDS_LOCATION"R2U34"
ROOM"SMBUS"
PART_NUMBER"G21796-173"
WATTAGE"1/16W"
TOLERANCE"1%"
VALUE"20.0"
LOCATION"R2U34"
MATERIAL"CHIP";
"B"
$PN"2"22;
"A"
$PN"1"31;
%"RES"
"1","(-3175,3775)","0","mstr_discrete","I231";
;
PACK_TYPE"0402"
BOM_COST"SM_CONTROLLER"
CDS_SEC"1"
$SEC"1"
ROOM"SMBUS"
PART_NUMBER"G21796-173"
CDS_LOCATION"R2U33"
CDS_LIB"mstr_discrete"
WATTAGE"1/16W"
TOLERANCE"1%"
VALUE"20.0"
LOCATION"R2U33"
MATERIAL"CHIP";
"B"
$PN"2"1;
"A"
$PN"1"32;
%"RES"
"1","(-3175,4200)","0","mstr_discrete","I232";
;
CDS_SEC"1"
$SEC"1"
BOM_COST"SM_CONTROLLER"
CDS_LIB"mstr_discrete"
PART_NUMBER"G21796-173"
CDS_LOCATION"R1U9"
ROOM"SMBUS"
WATTAGE"1/16W"
PACK_TYPE"0402"
TOLERANCE"1%"
VALUE"20.0"
LOCATION"R1U9"
MATERIAL"CHIP";
"B"
$PN"2"18;
"A"
$PN"1"33;
%"RES"
"1","(-3175,4375)","0","mstr_discrete","I233";
;
PACK_TYPE"0402"
CDS_SEC"1"
$SEC"1"
CDS_LIB"mstr_discrete"
ROOM"SMBUS"
BOM_COST"SM_CONTROLLER"
CDS_LOCATION"R1U10"
PART_NUMBER"G21796-173"
WATTAGE"1/16W"
TOLERANCE"1%"
VALUE"20.0"
LOCATION"R1U10"
MATERIAL"CHIP";
"B"
$PN"2"19;
"A"
$PN"1"34;
END.
